(kicad_pcb
	(version 20211014)
	(generator pcbnew)
	(general
    (thickness 1.6)
  )
	(paper "A4")
	(title_block
    (title "SA800U (Snapdragon 845) Baseboard")
    (date "2023-10-19")
    (rev "1.0.3")
    (company "Antmicro Ltd.")
    (comment 1 "www.antmicro.com")
		(comment 9 "footprints 373-381 of 589")
	)
	(layers
    (0 "F.Cu" signal)
    (1 "In1.Cu" power)
    (2 "In2.Cu" signal)
    (3 "In3.Cu" signal)
    (4 "In4.Cu" power)
    (31 "B.Cu" signal)
    (32 "B.Adhes" user "B.Adhesive")
    (33 "F.Adhes" user "F.Adhesive")
    (34 "B.Paste" user)
    (35 "F.Paste" user)
    (36 "B.SilkS" user "B.Silkscreen")
    (37 "F.SilkS" user "F.Silkscreen")
    (38 "B.Mask" user)
    (39 "F.Mask" user)
    (40 "Dwgs.User" user "User.Drawings")
    (41 "Cmts.User" user "User.Comments")
    (42 "Eco1.User" user "User.Eco1")
    (43 "Eco2.User" user "User.Eco2")
    (44 "Edge.Cuts" user)
    (45 "Margin" user)
    (46 "B.CrtYd" user "B.Courtyard")
    (47 "F.CrtYd" user "F.Courtyard")
    (48 "B.Fab" user)
    (49 "F.Fab" user)
  )
	(footprint "sa800u-baseboard-hw-footprints:C_0402_1005Metric" (layer "B.Cu")
    (tedit 616D63CF)
    (at 93.928774 105.432933 180)
    (descr "Capacitor SMD 0402")
    (tags "capacitor SMD 0402")
    (property "Author" "Antmicro")
    (property "Dielectric" "X5R")
    (property "License" "Apache-2.0")
    (property "MPN" "GRM155R61H104KE14D")
    (property "Manufacturer" "Murata")
    (property "Sheetfile" "ethernet-controller.kicad_sch")
    (property "Sheetname" "Ethernet Controller")
    (property "Val" "100n")
    (property "Voltage" "50V")
    (attr smd)
    (fp_text reference "C5" (at -0.451226 0.612933) (layer "B.SilkS")
      (effects (font (size 0.7 0.7) (thickness 0.15)) (justify left bottom mirror))
    )
    (fp_text value "C_100n_0402" (at 0 -1.4) (layer "B.Fab")
      (effects (font (size 0.7 0.7) (thickness 0.15)) (justify left bottom mirror))
    )
    (fp_text user "${REFERENCE}" (at -0.932 -3.168) (layer "B.Fab") hide
      (effects (font (size 0.7 0.7) (thickness 0.15)) (justify left bottom mirror))
    )
    (fp_text user "License: Apache-2.0" (at -0.932 -5.17) (layer "B.Fab") hide
      (effects (font (size 0.7 0.7) (thickness 0.15)) (justify left bottom mirror))
    )
    (fp_text user "Author: Antmicro" (at -0.932 -4.17) (layer "B.Fab") hide
      (effects (font (size 0.7 0.7) (thickness 0.15)) (justify left bottom mirror))
    )
    (fp_rect (start -0.94 0.47) (end 0.94 -0.47) (layer "B.CrtYd") (width 0.05) (fill none))
    (fp_rect (start -0.499 0.249) (end 0.499 -0.249) (layer "B.Fab") (width 0.15) (fill none))
    (pad "1" smd roundrect (at -0.484 0 180) (size 0.59 0.64) (layers "B.Cu" "B.Paste" "B.Mask") (roundrect_rratio 0.25)
      (net 177 "/Ethernet Controller/ETH_3V3") (pintype "passive"))
    (pad "2" smd roundrect (at 0.484 0 180) (size 0.59 0.64) (layers "B.Cu" "B.Paste" "B.Mask") (roundrect_rratio 0.25)
      (net 1 "GND") (pintype "passive"))
  )
	(footprint "sa800u-baseboard-hw-footprints:C_0402_1005Metric" (layer "B.Cu")
    (tedit 616D63CF)
    (at 93.6 101.5 180)
    (descr "Capacitor SMD 0402")
    (tags "capacitor SMD 0402")
    (property "Author" "Antmicro")
    (property "Dielectric" "X5R")
    (property "License" "Apache-2.0")
    (property "MPN" "GRM155R61H104KE14D")
    (property "Manufacturer" "Murata")
    (property "Sheetfile" "ethernet-controller.kicad_sch")
    (property "Sheetname" "Ethernet Controller")
    (property "Val" "100n")
    (property "Voltage" "50V")
    (attr smd)
    (fp_text reference "C13" (at -0.82 -1.23) (layer "B.SilkS")
      (effects (font (size 0.7 0.7) (thickness 0.15)) (justify left bottom mirror))
    )
    (fp_text value "C_100n_0402" (at 0 -1.4) (layer "B.Fab")
      (effects (font (size 0.7 0.7) (thickness 0.15)) (justify left bottom mirror))
    )
    (fp_text user "License: Apache-2.0" (at -0.932 -5.17) (layer "B.Fab") hide
      (effects (font (size 0.7 0.7) (thickness 0.15)) (justify left bottom mirror))
    )
    (fp_text user "${REFERENCE}" (at -0.932 -3.168) (layer "B.Fab") hide
      (effects (font (size 0.7 0.7) (thickness 0.15)) (justify left bottom mirror))
    )
    (fp_text user "Author: Antmicro" (at -0.932 -4.17) (layer "B.Fab") hide
      (effects (font (size 0.7 0.7) (thickness 0.15)) (justify left bottom mirror))
    )
    (fp_rect (start -0.94 0.47) (end 0.94 -0.47) (layer "B.CrtYd") (width 0.05) (fill none))
    (fp_rect (start -0.499 0.249) (end 0.499 -0.249) (layer "B.Fab") (width 0.15) (fill none))
    (pad "1" smd roundrect (at -0.484 0 180) (size 0.59 0.64) (layers "B.Cu" "B.Paste" "B.Mask") (roundrect_rratio 0.25)
      (net 181 "/Ethernet Controller/ETH_1V0") (pintype "passive"))
    (pad "2" smd roundrect (at 0.484 0 180) (size 0.59 0.64) (layers "B.Cu" "B.Paste" "B.Mask") (roundrect_rratio 0.25)
      (net 1 "GND") (pintype "passive"))
  )
	(footprint "sa800u-baseboard-hw-footprints:C_0603_1608Metric" (layer "B.Cu")
    (tedit 5D5E94D2)
    (at 113.5 149.25 -90)
    (descr "Capacitor SMD 0603")
    (tags "capacitor 0603")
    (property "Author" "Antmicro")
    (property "Dielectric" "")
    (property "License" "Apache-2.0")
    (property "MPN" "GRM188R60J476ME15D")
    (property "Manufacturer" "Murata")
    (property "Sheetfile" "usb-c-interface.kicad_sch")
    (property "Sheetname" "USB-C Interface ")
    (property "Val" "47u")
    (property "Voltage" "")
    (attr smd)
    (fp_text reference "C78" (at -1.05 0.69 90) (layer "B.SilkS")
      (effects (font (size 0.7 0.7) (thickness 0.15)) (justify left bottom mirror))
    )
    (fp_text value "C_47u_0603" (at 0 -1.6 90) (layer "B.Fab")
      (effects (font (size 0.7 0.7) (thickness 0.15)) (justify left bottom mirror))
    )
    (fp_text user "${REFERENCE}" (at -1.682 -3.895 90) (layer "B.Fab") hide
      (effects (font (size 0.7 0.7) (thickness 0.15)) (justify left bottom mirror))
    )
    (fp_text user "Author: Antmicro" (at -1.682 -4.894 90) (layer "B.Fab") hide
      (effects (font (size 0.7 0.7) (thickness 0.15)) (justify left bottom mirror))
    )
    (fp_text user "License: Apache-2.0" (at -1.682 -5.895 90) (layer "B.Fab") hide
      (effects (font (size 0.7 0.7) (thickness 0.15)) (justify left bottom mirror))
    )
    (fp_line (start -0.3 0.3) (end 0.3 0.3) (layer "B.SilkS") (width 0.15))
    (fp_line (start -0.3 -0.3) (end 0.3 -0.3) (layer "B.SilkS") (width 0.15))
    (fp_rect (start -1.24 0.7) (end 1.24 -0.7) (layer "B.CrtYd") (width 0.05) (fill none))
    (fp_rect (start -0.8 0.4) (end 0.8 -0.4) (layer "B.Fab") (width 0.15) (fill none))
    (pad "1" smd roundrect (at -0.7 0 270) (size 0.6 0.8) (layers "B.Cu" "B.Paste" "B.Mask") (roundrect_rratio 0.2)
      (net 210 "/USB-C Interface /USB2_5V") (pintype "passive"))
    (pad "2" smd roundrect (at 0.7 0 270) (size 0.6 0.8) (layers "B.Cu" "B.Paste" "B.Mask") (roundrect_rratio 0.2)
      (net 1 "GND") (pintype "passive"))
  )
	(footprint "sa800u-baseboard-hw-footprints:Nexperia_DFN-10_2.5x1mm_P0.5mm" (layer "B.Cu")
    (tedit 6215DC23)
    (at 99 140.6)
    (property "Author" "Antmicro")
    (property "License" "Apache-2.0")
    (property "MPN" "PUSB3F96X")
    (property "Manufacturer" "Nexperia")
    (property "Sheetfile" "usb-c-interface.kicad_sch")
    (property "Sheetname" "USB-C Interface ")
    (attr smd)
    (fp_text reference "D9" (at 0.94 1.57 180) (layer "B.SilkS")
      (effects (font (size 0.7 0.7) (thickness 0.15)) (justify left bottom mirror))
    )
    (fp_text value "PUSB3F96X_PASS" (at -0.016 -1.705 180) (layer "B.Fab")
      (effects (font (size 0.7 0.7) (thickness 0.15)) (justify left bottom mirror))
    )
    (fp_text user "Author: Antmicro" (at -1.367 -4.905 180) (layer "B.Fab") hide
      (effects (font (size 0.7 0.7) (thickness 0.15)) (justify left bottom mirror))
    )
    (fp_text user "${REFERENCE}" (at -1.367 -3.704 180) (layer "B.Fab") hide
      (effects (font (size 0.7 0.7) (thickness 0.15)) (justify left bottom mirror))
    )
    (fp_text user "License: Apache-2.0" (at -1.367 -6.105 180) (layer "B.Fab") hide
      (effects (font (size 0.7 0.7) (thickness 0.15)) (justify left bottom mirror))
    )
    (fp_line (start 1.233 -0.405) (end 1.233 0.396) (layer "B.SilkS") (width 0.15))
    (fp_line (start -1.266 0.396) (end -1.266 -0.405) (layer "B.SilkS") (width 0.15))
    (fp_circle (center -1.317 -0.704) (end -1.266 -0.704) (layer "B.SilkS") (width 0.15) (fill solid))
    (fp_rect (start -1.4 0.7) (end 1.4 -0.7) (layer "B.CrtYd") (width 0.05) (fill none))
    (pad "1" smd rect (at -1.016 -0.392) (size 0.2 0.475) (layers "B.Cu" "B.Paste" "B.Mask")
      (net 308 "/USB-C Interface /USB1C_RX0_C_P") (pinfunction "CH1") (pintype "passive"))
    (pad "2" smd rect (at -0.517 -0.392) (size 0.2 0.475) (layers "B.Cu" "B.Paste" "B.Mask")
      (net 323 "/USB-C Interface /USB1C_RX0_C_N") (pinfunction "CH2") (pintype "passive"))
    (pad "3" smd rect (at -0.016 -0.392) (size 0.2 0.475) (layers "B.Cu" "B.Paste" "B.Mask")
      (net 1 "GND") (pinfunction "GND") (pintype "passive"))
    (pad "4" smd rect (at 0.482 -0.392) (size 0.2 0.475) (layers "B.Cu" "B.Paste" "B.Mask")
      (net 302 "/USB-C Interface /USB1C_TX0_C_P") (pinfunction "CH3") (pintype "passive"))
    (pad "5" smd rect (at 0.982 -0.392) (size 0.2 0.475) (layers "B.Cu" "B.Paste" "B.Mask")
      (net 303 "/USB-C Interface /USB1C_TX0_C_N") (pinfunction "CH4") (pintype "passive"))
    (pad "6" smd rect (at 0.982 0.383 180) (size 0.2 0.475) (layers "B.Cu" "B.Paste" "B.Mask")
      (net 303 "/USB-C Interface /USB1C_TX0_C_N") (pinfunction "CH4") (pintype "passive"))
    (pad "7" smd rect (at 0.482 0.383 180) (size 0.2 0.475) (layers "B.Cu" "B.Paste" "B.Mask")
      (net 302 "/USB-C Interface /USB1C_TX0_C_P") (pinfunction "CH3") (pintype "passive"))
    (pad "8" smd rect (at -0.016 0.383 180) (size 0.2 0.475) (layers "B.Cu" "B.Paste" "B.Mask")
      (net 1 "GND") (pinfunction "GND") (pintype "passive"))
    (pad "9" smd rect (at -0.517 0.383 180) (size 0.2 0.475) (layers "B.Cu" "B.Paste" "B.Mask")
      (net 323 "/USB-C Interface /USB1C_RX0_C_N") (pinfunction "CH2") (pintype "passive"))
    (pad "10" smd rect (at -1.016 0.383 180) (size 0.2 0.475) (layers "B.Cu" "B.Paste" "B.Mask")
      (net 308 "/USB-C Interface /USB1C_RX0_C_P") (pinfunction "CH1") (pintype "passive"))
  )
	(footprint "sa800u-baseboard-hw-footprints:C_0402_1005Metric" (layer "B.Cu")
    (tedit 616D63CF)
    (at 111.8 133.5 -90)
    (descr "Capacitor SMD 0402")
    (tags "capacitor SMD 0402")
    (property "Author" "Antmicro")
    (property "Dielectric" "X5R")
    (property "License" "Apache-2.0")
    (property "MPN" "GRM155R61H104KE14D")
    (property "Manufacturer" "Murata")
    (property "Sheetfile" "usb-c-interface.kicad_sch")
    (property "Sheetname" "USB-C Interface ")
    (property "Val" "100n")
    (property "Voltage" "50V")
    (attr smd)
    (fp_text reference "C74" (at -1 0.6 90) (layer "B.SilkS")
      (effects (font (size 0.7 0.7) (thickness 0.15)) (justify left bottom mirror))
    )
    (fp_text value "C_100n_0402" (at 0 -1.4 90) (layer "B.Fab")
      (effects (font (size 0.7 0.7) (thickness 0.15)) (justify left bottom mirror))
    )
    (fp_text user "Author: Antmicro" (at -0.932 -4.17 90) (layer "B.Fab") hide
      (effects (font (size 0.7 0.7) (thickness 0.15)) (justify left bottom mirror))
    )
    (fp_text user "License: Apache-2.0" (at -0.932 -5.17 90) (layer "B.Fab") hide
      (effects (font (size 0.7 0.7) (thickness 0.15)) (justify left bottom mirror))
    )
    (fp_text user "${REFERENCE}" (at -0.932 -3.168 90) (layer "B.Fab") hide
      (effects (font (size 0.7 0.7) (thickness 0.15)) (justify left bottom mirror))
    )
    (fp_rect (start -0.94 0.47) (end 0.94 -0.47) (layer "B.CrtYd") (width 0.05) (fill none))
    (fp_rect (start -0.499 0.249) (end 0.499 -0.249) (layer "B.Fab") (width 0.15) (fill none))
    (pad "1" smd roundrect (at -0.484 0 270) (size 0.59 0.64) (layers "B.Cu" "B.Paste" "B.Mask") (roundrect_rratio 0.25)
      (net 131 "3V3_SYS") (pintype "passive"))
    (pad "2" smd roundrect (at 0.484 0 270) (size 0.59 0.64) (layers "B.Cu" "B.Paste" "B.Mask") (roundrect_rratio 0.25)
      (net 1 "GND") (pintype "passive"))
  )
	(footprint "sa800u-baseboard-hw-footprints:C_0402_1005Metric" (layer "B.Cu")
    (tedit 616D63CF)
    (at 115.25 138.95 -90)
    (descr "Capacitor SMD 0402")
    (tags "capacitor SMD 0402")
    (property "Author" "Antmicro")
    (property "Dielectric" "X5R")
    (property "License" "Apache-2.0")
    (property "MPN" "GRM155R61H104KE14D")
    (property "Manufacturer" "Murata")
    (property "Sheetfile" "usb-c-interface.kicad_sch")
    (property "Sheetname" "USB-C Interface ")
    (property "Val" "100n")
    (property "Voltage" "50V")
    (attr smd)
    (fp_text reference "C81" (at -3.05 -0.34 90) (layer "B.SilkS")
      (effects (font (size 0.7 0.7) (thickness 0.15)) (justify left bottom mirror))
    )
    (fp_text value "C_100n_0402" (at 0 -1.4 90) (layer "B.Fab")
      (effects (font (size 0.7 0.7) (thickness 0.15)) (justify left bottom mirror))
    )
    (fp_text user "${REFERENCE}" (at -0.932 -3.168 90) (layer "B.Fab") hide
      (effects (font (size 0.7 0.7) (thickness 0.15)) (justify left bottom mirror))
    )
    (fp_text user "Author: Antmicro" (at -0.932 -4.17 90) (layer "B.Fab") hide
      (effects (font (size 0.7 0.7) (thickness 0.15)) (justify left bottom mirror))
    )
    (fp_text user "License: Apache-2.0" (at -0.932 -5.17 90) (layer "B.Fab") hide
      (effects (font (size 0.7 0.7) (thickness 0.15)) (justify left bottom mirror))
    )
    (fp_rect (start -0.94 0.47) (end 0.94 -0.47) (layer "B.CrtYd") (width 0.05) (fill none))
    (fp_rect (start -0.499 0.249) (end 0.499 -0.249) (layer "B.Fab") (width 0.15) (fill none))
    (pad "1" smd roundrect (at -0.484 0 270) (size 0.59 0.64) (layers "B.Cu" "B.Paste" "B.Mask") (roundrect_rratio 0.25)
      (net 212 "/USB-C Interface /USB2C_TX1_N") (pintype "passive"))
    (pad "2" smd roundrect (at 0.484 0 270) (size 0.59 0.64) (layers "B.Cu" "B.Paste" "B.Mask") (roundrect_rratio 0.25)
      (net 211 "/USB-C Interface /USB2C_TX1_C_N") (pintype "passive"))
  )
	(footprint "sa800u-baseboard-hw-footprints:C_0402_1005Metric" (layer "B.Cu")
    (tedit 616D63CF)
    (at 116.25 138.95 -90)
    (descr "Capacitor SMD 0402")
    (tags "capacitor SMD 0402")
    (property "Author" "Antmicro")
    (property "Dielectric" "X5R")
    (property "License" "Apache-2.0")
    (property "MPN" "GRM155R61H104KE14D")
    (property "Manufacturer" "Murata")
    (property "Sheetfile" "usb-c-interface.kicad_sch")
    (property "Sheetname" "USB-C Interface ")
    (property "Val" "100n")
    (property "Voltage" "50V")
    (attr smd)
    (fp_text reference "C82" (at -3.05 -0.34 90) (layer "B.SilkS")
      (effects (font (size 0.7 0.7) (thickness 0.15)) (justify left bottom mirror))
    )
    (fp_text value "C_100n_0402" (at 0 -1.4 90) (layer "B.Fab")
      (effects (font (size 0.7 0.7) (thickness 0.15)) (justify left bottom mirror))
    )
    (fp_text user "License: Apache-2.0" (at -0.932 -5.17 90) (layer "B.Fab") hide
      (effects (font (size 0.7 0.7) (thickness 0.15)) (justify left bottom mirror))
    )
    (fp_text user "Author: Antmicro" (at -0.932 -4.17 90) (layer "B.Fab") hide
      (effects (font (size 0.7 0.7) (thickness 0.15)) (justify left bottom mirror))
    )
    (fp_text user "${REFERENCE}" (at -0.932 -3.168 90) (layer "B.Fab") hide
      (effects (font (size 0.7 0.7) (thickness 0.15)) (justify left bottom mirror))
    )
    (fp_rect (start -0.94 0.47) (end 0.94 -0.47) (layer "B.CrtYd") (width 0.05) (fill none))
    (fp_rect (start -0.499 0.249) (end 0.499 -0.249) (layer "B.Fab") (width 0.15) (fill none))
    (pad "1" smd roundrect (at -0.484 0 270) (size 0.59 0.64) (layers "B.Cu" "B.Paste" "B.Mask") (roundrect_rratio 0.25)
      (net 214 "/USB-C Interface /USB2C_RX2_P") (pintype "passive"))
    (pad "2" smd roundrect (at 0.484 0 270) (size 0.59 0.64) (layers "B.Cu" "B.Paste" "B.Mask") (roundrect_rratio 0.25)
      (net 213 "/USB-C Interface /USB2C_RX2_C_P") (pintype "passive"))
  )
	(footprint "sa800u-baseboard-hw-footprints:C_0402_1005Metric" (layer "B.Cu")
    (tedit 616D63CF)
    (at 117.25 138.95 -90)
    (descr "Capacitor SMD 0402")
    (tags "capacitor SMD 0402")
    (property "Author" "Antmicro")
    (property "Dielectric" "X5R")
    (property "License" "Apache-2.0")
    (property "MPN" "GRM155R61H104KE14D")
    (property "Manufacturer" "Murata")
    (property "Sheetfile" "usb-c-interface.kicad_sch")
    (property "Sheetname" "USB-C Interface ")
    (property "Val" "100n")
    (property "Voltage" "50V")
    (attr smd)
    (fp_text reference "C86" (at -3.05 -0.34 90) (layer "B.SilkS")
      (effects (font (size 0.7 0.7) (thickness 0.15)) (justify left bottom mirror))
    )
    (fp_text value "C_100n_0402" (at 0 -1.4 90) (layer "B.Fab")
      (effects (font (size 0.7 0.7) (thickness 0.15)) (justify left bottom mirror))
    )
    (fp_text user "Author: Antmicro" (at -0.932 -4.17 90) (layer "B.Fab") hide
      (effects (font (size 0.7 0.7) (thickness 0.15)) (justify left bottom mirror))
    )
    (fp_text user "License: Apache-2.0" (at -0.932 -5.17 90) (layer "B.Fab") hide
      (effects (font (size 0.7 0.7) (thickness 0.15)) (justify left bottom mirror))
    )
    (fp_text user "${REFERENCE}" (at -0.932 -3.168 90) (layer "B.Fab") hide
      (effects (font (size 0.7 0.7) (thickness 0.15)) (justify left bottom mirror))
    )
    (fp_rect (start -0.94 0.47) (end 0.94 -0.47) (layer "B.CrtYd") (width 0.05) (fill none))
    (fp_rect (start -0.499 0.249) (end 0.499 -0.249) (layer "B.Fab") (width 0.15) (fill none))
    (pad "1" smd roundrect (at -0.484 0 270) (size 0.59 0.64) (layers "B.Cu" "B.Paste" "B.Mask") (roundrect_rratio 0.25)
      (net 218 "/USB-C Interface /USB2C_RX2_N") (pintype "passive"))
    (pad "2" smd roundrect (at 0.484 0 270) (size 0.59 0.64) (layers "B.Cu" "B.Paste" "B.Mask") (roundrect_rratio 0.25)
      (net 217 "/USB-C Interface /USB2C_RX2_C_N") (pintype "passive"))
  )
	(footprint "sa800u-baseboard-hw-footprints:C_0402_1005Metric" (layer "B.Cu")
    (tedit 616D63CF)
    (at 113.25 138.95 -90)
    (descr "Capacitor SMD 0402")
    (tags "capacitor SMD 0402")
    (property "Author" "Antmicro")
    (property "Dielectric" "X5R")
    (property "License" "Apache-2.0")
    (property "MPN" "GRM155R61H104KE14D")
    (property "Manufacturer" "Murata")
    (property "Sheetfile" "usb-c-interface.kicad_sch")
    (property "Sheetname" "USB-C Interface ")
    (property "Val" "100n")
    (property "Voltage" "50V")
    (attr smd)
    (fp_text reference "C90" (at -3.05 -0.34 90) (layer "B.SilkS")
      (effects (font (size 0.7 0.7) (thickness 0.15)) (justify left bottom mirror))
    )
    (fp_text value "C_100n_0402" (at 0 -1.4 90) (layer "B.Fab")
      (effects (font (size 0.7 0.7) (thickness 0.15)) (justify left bottom mirror))
    )
    (fp_text user "Author: Antmicro" (at -0.932 -4.17 90) (layer "B.Fab") hide
      (effects (font (size 0.7 0.7) (thickness 0.15)) (justify left bottom mirror))
    )
    (fp_text user "License: Apache-2.0" (at -0.932 -5.17 90) (layer "B.Fab") hide
      (effects (font (size 0.7 0.7) (thickness 0.15)) (justify left bottom mirror))
    )
    (fp_text user "${REFERENCE}" (at -0.932 -3.168 90) (layer "B.Fab") hide
      (effects (font (size 0.7 0.7) (thickness 0.15)) (justify left bottom mirror))
    )
    (fp_rect (start -0.94 0.47) (end 0.94 -0.47) (layer "B.CrtYd") (width 0.05) (fill none))
    (fp_rect (start -0.499 0.249) (end 0.499 -0.249) (layer "B.Fab") (width 0.15) (fill none))
    (pad "1" smd roundrect (at -0.484 0 270) (size 0.59 0.64) (layers "B.Cu" "B.Paste" "B.Mask") (roundrect_rratio 0.25)
      (net 219 "/USB-C Interface /USB2C_RX1_N") (pintype "passive"))
    (pad "2" smd roundrect (at 0.484 0 270) (size 0.59 0.64) (layers "B.Cu" "B.Paste" "B.Mask") (roundrect_rratio 0.25)
      (net 220 "/USB-C Interface /USB2C_RX1_C_N") (pintype "passive"))
  )
)
